(kicad_pcb
	(version 20260206)
	(generator "pcbnew")
	(generator_version "10.0")
	(general
		(thickness 1.6)
		(legacy_teardrops no)
	)
	(paper "A4")
	(title_block
		(title "04192023_DAF0TMB3IC0_F0TG_MB_C_brd_V02_OCP.brd")
		(comment 1 "Grand Teton / footprints 2566-2571 of 8354")
	)
	(layers
		(0 "F.Cu" signal "TOP")
		(4 "In1.Cu" signal "GND")
		(6 "In2.Cu" signal "IN1")
		(8 "In3.Cu" signal "GND1")
		(10 "In4.Cu" signal "IN2")
		(12 "In5.Cu" signal "GND2")
		(14 "In6.Cu" signal "IN3")
		(16 "In7.Cu" signal "GND3")
		(18 "In8.Cu" signal "VCC")
		(20 "In9.Cu" signal "VCC1")
		(22 "In10.Cu" signal "GND4")
		(24 "In11.Cu" signal "IN4")
		(26 "In12.Cu" signal "GND5")
		(28 "In13.Cu" signal "IN5")
		(30 "In14.Cu" signal "GND6")
		(32 "In15.Cu" signal "IN6")
		(34 "In16.Cu" signal "GND7")
		(2 "B.Cu" signal "BOTTOM")
		(9 "F.Adhes" user "F.Adhesive")
		(11 "B.Adhes" user "B.Adhesive")
		(13 "F.Paste" user "Package Geometry/Pastemask Top")
		(15 "B.Paste" user "Package Geometry/Pastemask Bottom")
		(5 "F.SilkS" user "Ref Des/Silkscreen Top")
		(7 "B.SilkS" user "Ref Des/Silkscreen Bottom")
		(1 "F.Mask" user "Board Geometry/Soldermask Top")
		(3 "B.Mask" user "Board Geometry/Soldermask Bottom")
		(17 "Dwgs.User" user "User.Drawings")
		(19 "Cmts.User" user "User.Comments")
		(21 "Eco1.User" user "User.Eco1")
		(23 "Eco2.User" user "User.Eco2")
		(25 "Edge.Cuts" user "Board Geometry/Outline")
		(27 "Margin" user)
		(31 "F.CrtYd" user "Package Geometry/Place Bound Top")
		(29 "B.CrtYd" user "Package Geometry/Place Bound Bottom")
		(35 "F.Fab" user "Ref Des/Assembly Top")
		(33 "B.Fab" user "Ref Des/Assembly Bottom")
	)
	(footprint ""
		(layer "F.Cu")
		(at 19.241516 -37.894514 180)
		(property "Reference" "R1271"
			(at 0 0 180)
			(layer "F.SilkS")
			(hide yes)
			(effects
				(font
					(size 1.27 1.27)
				)
			)
		)
		(property "Value" ""
			(at 0 0 180)
			(layer "F.Fab")
			(effects
				(font
					(size 1.27 1.27)
				)
			)
		)
		(duplicate_pad_numbers_are_jumpers no)
		(fp_line
			(start 0.7874 0.4064)
			(end -0.7874 0.4064)
			(stroke
				(width 0.1524)
				(type default)
			)
			(layer "F.SilkS")
		)
		(fp_line
			(start 0.7874 -0.4064)
			(end 0.7874 0.4064)
			(stroke
				(width 0.1524)
				(type default)
			)
			(layer "F.SilkS")
		)
		(fp_line
			(start -0.7874 0.4064)
			(end -0.7874 -0.4064)
			(stroke
				(width 0.1524)
				(type default)
			)
			(layer "F.SilkS")
		)
		(fp_line
			(start -0.7874 -0.4064)
			(end 0.7874 -0.4064)
			(stroke
				(width 0.1524)
				(type default)
			)
			(layer "F.SilkS")
		)
		(fp_line
			(start 0.67945 0.3048)
			(end 0.120396 0.3048)
			(stroke
				(width 0.1)
				(type default)
			)
			(layer "F.Fab")
		)
		(fp_line
			(start 0.67945 -0.3048)
			(end 0.67945 0.3048)
			(stroke
				(width 0.1)
				(type default)
			)
			(layer "F.Fab")
		)
		(fp_line
			(start 0.12065 -0.2794)
			(end 0.12065 -0.3048)
			(stroke
				(width 0.1)
				(type default)
			)
			(layer "F.Fab")
		)
		(fp_line
			(start 0.12065 -0.3048)
			(end 0.67945 -0.3048)
			(stroke
				(width 0.1)
				(type default)
			)
			(layer "F.Fab")
		)
		(fp_line
			(start 0.120396 0.3048)
			(end 0.120396 0.2794)
			(stroke
				(width 0.1)
				(type default)
			)
			(layer "F.Fab")
		)
		(fp_line
			(start 0.120396 0.2794)
			(end -0.12065 0.2794)
			(stroke
				(width 0.1)
				(type default)
			)
			(layer "F.Fab")
		)
		(fp_line
			(start -0.12065 0.3048)
			(end -0.67945 0.3048)
			(stroke
				(width 0.1)
				(type default)
			)
			(layer "F.Fab")
		)
		(fp_line
			(start -0.12065 0.2794)
			(end -0.12065 0.3048)
			(stroke
				(width 0.1)
				(type default)
			)
			(layer "F.Fab")
		)
		(fp_line
			(start -0.12065 -0.2794)
			(end 0.12065 -0.2794)
			(stroke
				(width 0.1)
				(type default)
			)
			(layer "F.Fab")
		)
		(fp_line
			(start -0.12065 -0.305054)
			(end -0.12065 -0.2794)
			(stroke
				(width 0.1)
				(type default)
			)
			(layer "F.Fab")
		)
		(fp_line
			(start -0.67945 0.3048)
			(end -0.67945 -0.305054)
			(stroke
				(width 0.1)
				(type default)
			)
			(layer "F.Fab")
		)
		(fp_line
			(start -0.67945 -0.305054)
			(end -0.12065 -0.305054)
			(stroke
				(width 0.1)
				(type default)
			)
			(layer "F.Fab")
		)
		(pad "1" smd circle
			(at -0.40005 0 180)
			(size 0 0)
			(layers "F.Cu" "F.Mask" "F.Paste")
			(net "P12V_OCP_V3_2_ADC_ALERT_R")
		)
		(pad "2" smd circle
			(at 0.40005 0 180)
			(size 0 0)
			(layers "F.Cu" "F.Mask" "F.Paste")
			(net "OCP_V3_2_P3V3_P12V_ADC_R_ALERT")
		)
	)
	(footprint ""
		(layer "F.Cu")
		(at 403.476714 -147.706588)
		(property "Reference" "Q57"
			(at -2.2225 -3.470402 0)
			(unlocked yes)
			(layer "F.SilkS")
			(effects
				(font
					(size 0.7874 0.5842)
					(thickness 0.1524)
				)
				(justify left)
			)
		)
		(property "Value" ""
			(at 0 0 0)
			(layer "F.Fab")
			(effects
				(font
					(size 1.27 1.27)
				)
			)
		)
		(duplicate_pad_numbers_are_jumpers no)
		(fp_line
			(start -2.350008 -2.649982)
			(end 2.350008 -2.649982)
			(stroke
				(width 0.1524)
				(type default)
			)
			(layer "F.SilkS")
		)
		(fp_line
			(start -2.350008 -2.4384)
			(end -2.350008 -2.649982)
			(stroke
				(width 0.1524)
				(type default)
			)
			(layer "F.SilkS")
		)
		(fp_line
			(start -2.350008 2.649982)
			(end -2.350008 2.413)
			(stroke
				(width 0.1524)
				(type default)
			)
			(layer "F.SilkS")
		)
		(fp_line
			(start 2.350008 -2.649982)
			(end 2.350008 -2.4892)
			(stroke
				(width 0.1524)
				(type default)
			)
			(layer "F.SilkS")
		)
		(fp_line
			(start 2.350008 2.4892)
			(end 2.350008 2.649982)
			(stroke
				(width 0.1524)
				(type default)
			)
			(layer "F.SilkS")
		)
		(fp_line
			(start 2.350008 2.649982)
			(end -2.350008 2.649982)
			(stroke
				(width 0.1524)
				(type default)
			)
			(layer "F.SilkS")
		)
		(fp_poly
			(pts
				(xy -5.142992 -3.626866) (xy -4.444238 -2.74828) (xy -5.537962 -2.930906)
			)
			(stroke
				(width 0)
				(type default)
			)
			(fill yes)
			(layer "F.SilkS")
		)
		(fp_line
			(start -2.350008 -2.649982)
			(end 2.350008 -2.649982)
			(stroke
				(width 0.1)
				(type default)
			)
			(layer "F.Fab")
		)
		(fp_line
			(start -2.350008 2.649982)
			(end -2.350008 -2.649982)
			(stroke
				(width 0.1)
				(type default)
			)
			(layer "F.Fab")
		)
		(fp_line
			(start 2.350008 -2.649982)
			(end 2.350008 2.649982)
			(stroke
				(width 0.1)
				(type default)
			)
			(layer "F.Fab")
		)
		(fp_line
			(start 2.350008 2.649982)
			(end -2.350008 2.649982)
			(stroke
				(width 0.1)
				(type default)
			)
			(layer "F.Fab")
		)
		(fp_poly
			(pts
				(xy -3.717544 -1.905) (xy -4.758944 -2.3241) (xy -4.758944 -1.524)
			)
			(stroke
				(width 0)
				(type default)
			)
			(fill yes)
			(layer "F.Fab")
		)
		(pad "1" smd rect
			(at -2.999994 -1.905 270)
			(size 0.7112 1.1684)
			(layers "F.Cu" "F.Mask" "F.Paste")
			(net "P5V")
		)
		(pad "2" smd rect
			(at -2.999994 -0.635 270)
			(size 0.7112 1.1684)
			(layers "F.Cu" "F.Mask" "F.Paste")
			(net "P5V")
		)
		(pad "3" smd rect
			(at -2.999994 0.635 270)
			(size 0.7112 1.1684)
			(layers "F.Cu" "F.Mask" "F.Paste")
			(net "P5V")
		)
		(pad "4" smd rect
			(at -2.999994 1.905 270)
			(size 0.7112 1.1684)
			(layers "F.Cu" "F.Mask" "F.Paste")
			(net "VR_P5V_EN_D_R")
		)
		(pad "5" smd circle
			(at 0.925068 0 270)
			(size 0 0)
			(layers "F.Cu" "F.Mask" "F.Paste")
			(net "P5V_AUX")
		)
		(zone
			(layer "F.Cu")
			(hatch none 0.5)
			(connect_pads
				(clearance 0)
			)
			(min_thickness 0.25)
			(keepout
				(tracks not_allowed)
				(vias allowed)
				(pads allowed)
				(copperpour not_allowed)
				(footprints allowed)
			)
			(placement
				(enabled no)
				(sheetname "")
			)
			(fill
				(thermal_gap 0.5)
				(thermal_bridge_width 0.5)
				(island_removal_mode 0)
			)
			(polygon
				(pts
					(xy 402.086064 -149.865588) (xy 402.028914 -149.865588) (xy 402.028914 -145.547588) (xy 402.091144 -145.547588)
					(xy 402.091144 -145.064988) (xy 401.127214 -145.064988) (xy 401.127214 -150.348188) (xy 402.086064 -150.348188)
				)
			)
		)
	)
	(footprint ""
		(layer "F.Cu")
		(at 399.128742 -171.959524)
		(property "Reference" "PR358"
			(at 0 0 0)
			(layer "F.SilkS")
			(hide yes)
			(effects
				(font
					(size 1.27 1.27)
				)
			)
		)
		(property "Value" ""
			(at 0 0 0)
			(layer "F.Fab")
			(effects
				(font
					(size 1.27 1.27)
				)
			)
		)
		(duplicate_pad_numbers_are_jumpers no)
		(fp_line
			(start -0.7874 -0.4064)
			(end 0.7874 -0.4064)
			(stroke
				(width 0.1524)
				(type default)
			)
			(layer "F.SilkS")
		)
		(fp_line
			(start -0.7874 0.4064)
			(end -0.7874 -0.4064)
			(stroke
				(width 0.1524)
				(type default)
			)
			(layer "F.SilkS")
		)
		(fp_line
			(start 0.7874 -0.4064)
			(end 0.7874 0.4064)
			(stroke
				(width 0.1524)
				(type default)
			)
			(layer "F.SilkS")
		)
		(fp_line
			(start 0.7874 0.4064)
			(end -0.7874 0.4064)
			(stroke
				(width 0.1524)
				(type default)
			)
			(layer "F.SilkS")
		)
		(fp_line
			(start -0.67945 -0.305054)
			(end -0.12065 -0.305054)
			(stroke
				(width 0.1)
				(type default)
			)
			(layer "F.Fab")
		)
		(fp_line
			(start -0.67945 0.3048)
			(end -0.67945 -0.305054)
			(stroke
				(width 0.1)
				(type default)
			)
			(layer "F.Fab")
		)
		(fp_line
			(start -0.12065 -0.305054)
			(end -0.12065 -0.2794)
			(stroke
				(width 0.1)
				(type default)
			)
			(layer "F.Fab")
		)
		(fp_line
			(start -0.12065 -0.2794)
			(end 0.12065 -0.2794)
			(stroke
				(width 0.1)
				(type default)
			)
			(layer "F.Fab")
		)
		(fp_line
			(start -0.12065 0.2794)
			(end -0.12065 0.3048)
			(stroke
				(width 0.1)
				(type default)
			)
			(layer "F.Fab")
		)
		(fp_line
			(start -0.12065 0.3048)
			(end -0.67945 0.3048)
			(stroke
				(width 0.1)
				(type default)
			)
			(layer "F.Fab")
		)
		(fp_line
			(start 0.120396 0.2794)
			(end -0.12065 0.2794)
			(stroke
				(width 0.1)
				(type default)
			)
			(layer "F.Fab")
		)
		(fp_line
			(start 0.120396 0.3048)
			(end 0.120396 0.2794)
			(stroke
				(width 0.1)
				(type default)
			)
			(layer "F.Fab")
		)
		(fp_line
			(start 0.12065 -0.3048)
			(end 0.67945 -0.3048)
			(stroke
				(width 0.1)
				(type default)
			)
			(layer "F.Fab")
		)
		(fp_line
			(start 0.12065 -0.2794)
			(end 0.12065 -0.3048)
			(stroke
				(width 0.1)
				(type default)
			)
			(layer "F.Fab")
		)
		(fp_line
			(start 0.67945 -0.3048)
			(end 0.67945 0.3048)
			(stroke
				(width 0.1)
				(type default)
			)
			(layer "F.Fab")
		)
		(fp_line
			(start 0.67945 0.3048)
			(end 0.120396 0.3048)
			(stroke
				(width 0.1)
				(type default)
			)
			(layer "F.Fab")
		)
		(pad "1" smd circle
			(at -0.40005 0)
			(size 0 0)
			(layers "F.Cu" "F.Mask" "F.Paste")
			(net "GND")
		)
		(pad "2" smd circle
			(at 0.40005 0)
			(size 0 0)
			(layers "F.Cu" "F.Mask" "F.Paste")
			(net "PVDDCR_SOC_P0_LSET1")
		)
	)
	(footprint ""
		(layer "F.Cu")
		(at 116.990114 -166.711884)
		(property "Reference" "PR207"
			(at 0 0 0)
			(layer "F.SilkS")
			(hide yes)
			(effects
				(font
					(size 1.27 1.27)
				)
			)
		)
		(property "Value" ""
			(at 0 0 0)
			(layer "F.Fab")
			(effects
				(font
					(size 1.27 1.27)
				)
			)
		)
		(duplicate_pad_numbers_are_jumpers no)
		(fp_line
			(start -0.7874 -0.4064)
			(end 0.7874 -0.4064)
			(stroke
				(width 0.1524)
				(type default)
			)
			(layer "F.SilkS")
		)
		(fp_line
			(start -0.7874 0.4064)
			(end -0.7874 -0.4064)
			(stroke
				(width 0.1524)
				(type default)
			)
			(layer "F.SilkS")
		)
		(fp_line
			(start 0.7874 -0.4064)
			(end 0.7874 0.4064)
			(stroke
				(width 0.1524)
				(type default)
			)
			(layer "F.SilkS")
		)
		(fp_line
			(start 0.7874 0.4064)
			(end -0.7874 0.4064)
			(stroke
				(width 0.1524)
				(type default)
			)
			(layer "F.SilkS")
		)
		(fp_line
			(start -0.67945 -0.305054)
			(end -0.12065 -0.305054)
			(stroke
				(width 0.1)
				(type default)
			)
			(layer "F.Fab")
		)
		(fp_line
			(start -0.67945 0.3048)
			(end -0.67945 -0.305054)
			(stroke
				(width 0.1)
				(type default)
			)
			(layer "F.Fab")
		)
		(fp_line
			(start -0.12065 -0.305054)
			(end -0.12065 -0.2794)
			(stroke
				(width 0.1)
				(type default)
			)
			(layer "F.Fab")
		)
		(fp_line
			(start -0.12065 -0.2794)
			(end 0.12065 -0.2794)
			(stroke
				(width 0.1)
				(type default)
			)
			(layer "F.Fab")
		)
		(fp_line
			(start -0.12065 0.2794)
			(end -0.12065 0.3048)
			(stroke
				(width 0.1)
				(type default)
			)
			(layer "F.Fab")
		)
		(fp_line
			(start -0.12065 0.3048)
			(end -0.67945 0.3048)
			(stroke
				(width 0.1)
				(type default)
			)
			(layer "F.Fab")
		)
		(fp_line
			(start 0.120396 0.2794)
			(end -0.12065 0.2794)
			(stroke
				(width 0.1)
				(type default)
			)
			(layer "F.Fab")
		)
		(fp_line
			(start 0.120396 0.3048)
			(end 0.120396 0.2794)
			(stroke
				(width 0.1)
				(type default)
			)
			(layer "F.Fab")
		)
		(fp_line
			(start 0.12065 -0.3048)
			(end 0.67945 -0.3048)
			(stroke
				(width 0.1)
				(type default)
			)
			(layer "F.Fab")
		)
		(fp_line
			(start 0.12065 -0.2794)
			(end 0.12065 -0.3048)
			(stroke
				(width 0.1)
				(type default)
			)
			(layer "F.Fab")
		)
		(fp_line
			(start 0.67945 -0.3048)
			(end 0.67945 0.3048)
			(stroke
				(width 0.1)
				(type default)
			)
			(layer "F.Fab")
		)
		(fp_line
			(start 0.67945 0.3048)
			(end 0.120396 0.3048)
			(stroke
				(width 0.1)
				(type default)
			)
			(layer "F.Fab")
		)
		(pad "1" smd circle
			(at -0.40005 0)
			(size 0 0)
			(layers "F.Cu" "F.Mask" "F.Paste")
			(net "GND")
		)
		(pad "2" smd circle
			(at 0.40005 0)
			(size 0 0)
			(layers "F.Cu" "F.Mask" "F.Paste")
			(net "PVDDCR_SOC_P1_LSET1")
		)
	)
	(footprint ""
		(layer "F.Cu")
		(at 106.235754 -26.453592)
		(property "Reference" "R6257"
			(at 0 0 0)
			(layer "F.SilkS")
			(hide yes)
			(effects
				(font
					(size 1.27 1.27)
				)
			)
		)
		(property "Value" ""
			(at 0 0 0)
			(layer "F.Fab")
			(effects
				(font
					(size 1.27 1.27)
				)
			)
		)
		(duplicate_pad_numbers_are_jumpers no)
		(fp_line
			(start -0.7874 -0.4064)
			(end 0.7874 -0.4064)
			(stroke
				(width 0.1524)
				(type default)
			)
			(layer "F.SilkS")
		)
		(fp_line
			(start -0.7874 0.4064)
			(end -0.7874 -0.4064)
			(stroke
				(width 0.1524)
				(type default)
			)
			(layer "F.SilkS")
		)
		(fp_line
			(start 0.7874 -0.4064)
			(end 0.7874 0.4064)
			(stroke
				(width 0.1524)
				(type default)
			)
			(layer "F.SilkS")
		)
		(fp_line
			(start 0.7874 0.4064)
			(end -0.7874 0.4064)
			(stroke
				(width 0.1524)
				(type default)
			)
			(layer "F.SilkS")
		)
		(fp_line
			(start -0.67945 -0.305054)
			(end -0.12065 -0.305054)
			(stroke
				(width 0.1)
				(type default)
			)
			(layer "F.Fab")
		)
		(fp_line
			(start -0.67945 0.3048)
			(end -0.67945 -0.305054)
			(stroke
				(width 0.1)
				(type default)
			)
			(layer "F.Fab")
		)
		(fp_line
			(start -0.12065 -0.305054)
			(end -0.12065 -0.2794)
			(stroke
				(width 0.1)
				(type default)
			)
			(layer "F.Fab")
		)
		(fp_line
			(start -0.12065 -0.2794)
			(end 0.12065 -0.2794)
			(stroke
				(width 0.1)
				(type default)
			)
			(layer "F.Fab")
		)
		(fp_line
			(start -0.12065 0.2794)
			(end -0.12065 0.3048)
			(stroke
				(width 0.1)
				(type default)
			)
			(layer "F.Fab")
		)
		(fp_line
			(start -0.12065 0.3048)
			(end -0.67945 0.3048)
			(stroke
				(width 0.1)
				(type default)
			)
			(layer "F.Fab")
		)
		(fp_line
			(start 0.120396 0.2794)
			(end -0.12065 0.2794)
			(stroke
				(width 0.1)
				(type default)
			)
			(layer "F.Fab")
		)
		(fp_line
			(start 0.120396 0.3048)
			(end 0.120396 0.2794)
			(stroke
				(width 0.1)
				(type default)
			)
			(layer "F.Fab")
		)
		(fp_line
			(start 0.12065 -0.3048)
			(end 0.67945 -0.3048)
			(stroke
				(width 0.1)
				(type default)
			)
			(layer "F.Fab")
		)
		(fp_line
			(start 0.12065 -0.2794)
			(end 0.12065 -0.3048)
			(stroke
				(width 0.1)
				(type default)
			)
			(layer "F.Fab")
		)
		(fp_line
			(start 0.67945 -0.3048)
			(end 0.67945 0.3048)
			(stroke
				(width 0.1)
				(type default)
			)
			(layer "F.Fab")
		)
		(fp_line
			(start 0.67945 0.3048)
			(end 0.120396 0.3048)
			(stroke
				(width 0.1)
				(type default)
			)
			(layer "F.Fab")
		)
		(pad "1" smd circle
			(at -0.40005 0)
			(size 0 0)
			(layers "F.Cu" "F.Mask" "F.Paste")
			(net "XTAL_USB_CPU0_HUB2_XOUT")
		)
		(pad "2" smd circle
			(at 0.40005 0)
			(size 0 0)
			(layers "F.Cu" "F.Mask" "F.Paste")
			(net "XTAL_USB_CPU0_HUB2_XIN")
		)
	)
	(footprint ""
		(layer "F.Cu")
		(at 140.886942 -101.494844)
		(property "Reference" "R2121"
			(at 0 0 0)
			(layer "F.SilkS")
			(hide yes)
			(effects
				(font
					(size 1.27 1.27)
				)
			)
		)
		(property "Value" ""
			(at 0 0 0)
			(layer "F.Fab")
			(effects
				(font
					(size 1.27 1.27)
				)
			)
		)
		(duplicate_pad_numbers_are_jumpers no)
		(fp_line
			(start -0.7874 -0.4064)
			(end 0.7874 -0.4064)
			(stroke
				(width 0.1524)
				(type default)
			)
			(layer "F.SilkS")
		)
		(fp_line
			(start -0.7874 0.4064)
			(end -0.7874 -0.4064)
			(stroke
				(width 0.1524)
				(type default)
			)
			(layer "F.SilkS")
		)
		(fp_line
			(start 0.7874 -0.4064)
			(end 0.7874 0.4064)
			(stroke
				(width 0.1524)
				(type default)
			)
			(layer "F.SilkS")
		)
		(fp_line
			(start 0.7874 0.4064)
			(end -0.7874 0.4064)
			(stroke
				(width 0.1524)
				(type default)
			)
			(layer "F.SilkS")
		)
		(fp_line
			(start -0.67945 -0.305054)
			(end -0.12065 -0.305054)
			(stroke
				(width 0.1)
				(type default)
			)
			(layer "F.Fab")
		)
		(fp_line
			(start -0.67945 0.3048)
			(end -0.67945 -0.305054)
			(stroke
				(width 0.1)
				(type default)
			)
			(layer "F.Fab")
		)
		(fp_line
			(start -0.12065 -0.305054)
			(end -0.12065 -0.2794)
			(stroke
				(width 0.1)
				(type default)
			)
			(layer "F.Fab")
		)
		(fp_line
			(start -0.12065 -0.2794)
			(end 0.12065 -0.2794)
			(stroke
				(width 0.1)
				(type default)
			)
			(layer "F.Fab")
		)
		(fp_line
			(start -0.12065 0.2794)
			(end -0.12065 0.3048)
			(stroke
				(width 0.1)
				(type default)
			)
			(layer "F.Fab")
		)
		(fp_line
			(start -0.12065 0.3048)
			(end -0.67945 0.3048)
			(stroke
				(width 0.1)
				(type default)
			)
			(layer "F.Fab")
		)
		(fp_line
			(start 0.120396 0.2794)
			(end -0.12065 0.2794)
			(stroke
				(width 0.1)
				(type default)
			)
			(layer "F.Fab")
		)
		(fp_line
			(start 0.120396 0.3048)
			(end 0.120396 0.2794)
			(stroke
				(width 0.1)
				(type default)
			)
			(layer "F.Fab")
		)
		(fp_line
			(start 0.12065 -0.3048)
			(end 0.67945 -0.3048)
			(stroke
				(width 0.1)
				(type default)
			)
			(layer "F.Fab")
		)
		(fp_line
			(start 0.12065 -0.2794)
			(end 0.12065 -0.3048)
			(stroke
				(width 0.1)
				(type default)
			)
			(layer "F.Fab")
		)
		(fp_line
			(start 0.67945 -0.3048)
			(end 0.67945 0.3048)
			(stroke
				(width 0.1)
				(type default)
			)
			(layer "F.Fab")
		)
		(fp_line
			(start 0.67945 0.3048)
			(end 0.120396 0.3048)
			(stroke
				(width 0.1)
				(type default)
			)
			(layer "F.Fab")
		)
		(pad "1" smd circle
			(at -0.40005 0)
			(size 0 0)
			(layers "F.Cu" "F.Mask" "F.Paste")
			(net "P3V3_AUX")
		)
		(pad "2" smd circle
			(at 0.40005 0)
			(size 0 0)
			(layers "F.Cu" "F.Mask" "F.Paste")
			(net "RST_PERST_BUF_M2_0_N")
		)
	)
)
